# T6G (Grand Teton) — schematic netlist excerpt (pin names and nets, part order shuffled) for the footprints in the layout excerpt that follows; sources: Cadence DE-HDL packaged netlist, KiCad conversion of 04192023_DAF0TMB3IC0_F0TG_MB_C_brd_V02_OCP.brd

C413  Q_CAP  4.7UF 6.3V 20% X6S  pkg 0402  page 345 : A = P0V9_CPU1_RT2_2A ; B = GND
R4572  Q_RES  0 5% EMPTY  pkg 0402LF  page 125 : A = GPU_3V3IO_RSVD1_FFU ; B = GPU_3V3IO_RSVD1_FFU_ISO

(kicad_pcb
	(version 20260206)
	(generator "pcbnew")
	(generator_version "10.0")
	(general
		(thickness 1.6)
		(legacy_teardrops no)
	)
	(paper "A4")
	(title_block
		(title "04192023_DAF0TMB3IC0_F0TG_MB_C_brd_V02_OCP.brd")
		(comment 1 "Grand Teton / footprints 7538-7539 of 8354")
	)
	(layers
		(0 "F.Cu" signal "TOP")
		(4 "In1.Cu" signal "GND")
		(6 "In2.Cu" signal "IN1")
		(8 "In3.Cu" signal "GND1")
		(10 "In4.Cu" signal "IN2")
		(12 "In5.Cu" signal "GND2")
		(14 "In6.Cu" signal "IN3")
		(16 "In7.Cu" signal "GND3")
		(18 "In8.Cu" signal "VCC")
		(20 "In9.Cu" signal "VCC1")
		(22 "In10.Cu" signal "GND4")
		(24 "In11.Cu" signal "IN4")
		(26 "In12.Cu" signal "GND5")
		(28 "In13.Cu" signal "IN5")
		(30 "In14.Cu" signal "GND6")
		(32 "In15.Cu" signal "IN6")
		(34 "In16.Cu" signal "GND7")
		(2 "B.Cu" signal "BOTTOM")
		(9 "F.Adhes" user "F.Adhesive")
		(11 "B.Adhes" user "B.Adhesive")
		(13 "F.Paste" user "Package Geometry/Pastemask Top")
		(15 "B.Paste" user "Package Geometry/Pastemask Bottom")
		(5 "F.SilkS" user "Ref Des/Silkscreen Top")
		(7 "B.SilkS" user "Ref Des/Silkscreen Bottom")
		(1 "F.Mask" user "Board Geometry/Soldermask Top")
		(3 "B.Mask" user "Board Geometry/Soldermask Bottom")
		(17 "Dwgs.User" user "User.Drawings")
		(19 "Cmts.User" user "User.Comments")
		(21 "Eco1.User" user "User.Eco1")
		(23 "Eco2.User" user "User.Eco2")
		(25 "Edge.Cuts" user "Board Geometry/Outline")
		(27 "Margin" user)
		(31 "F.CrtYd" user "Package Geometry/Place Bound Top")
		(29 "B.CrtYd" user "Package Geometry/Place Bound Bottom")
		(35 "F.Fab" user "Ref Des/Assembly Top")
		(33 "B.Fab" user "Ref Des/Assembly Bottom")
	)
	(footprint ""
		(layer "B.Cu")
		(at 146.115024 -391.340848 -90)
		(property "Reference" "C413"
			(at 0 0 90)
			(layer "B.SilkS")
			(hide yes)
			(effects
				(font
					(size 1.27 1.27)
				)
				(justify mirror)
			)
		)
		(property "Value" ""
			(at 0 0 90)
			(layer "B.Fab")
			(effects
				(font
					(size 1.27 1.27)
				)
				(justify mirror)
			)
		)
		(duplicate_pad_numbers_are_jumpers no)
		(fp_line
			(start -0.7874 0.4064)
			(end 0.7874 0.4064)
			(stroke
				(width 0.1524)
				(type default)
			)
			(layer "B.SilkS")
		)
		(fp_line
			(start 0.7874 0.4064)
			(end 0.7874 -0.4064)
			(stroke
				(width 0.1524)
				(type default)
			)
			(layer "B.SilkS")
		)
		(fp_line
			(start -0.7874 -0.4064)
			(end -0.7874 0.4064)
			(stroke
				(width 0.1524)
				(type default)
			)
			(layer "B.SilkS")
		)
		(fp_line
			(start 0.7874 -0.4064)
			(end -0.7874 -0.4064)
			(stroke
				(width 0.1524)
				(type default)
			)
			(layer "B.SilkS")
		)
		(fp_line
			(start -0.67945 0.3048)
			(end -0.120396 0.3048)
			(stroke
				(width 0.1)
				(type default)
			)
			(layer "B.Fab")
		)
		(fp_line
			(start -0.120396 0.3048)
			(end -0.120396 0.2794)
			(stroke
				(width 0.1)
				(type default)
			)
			(layer "B.Fab")
		)
		(fp_line
			(start 0.12065 0.3048)
			(end 0.67945 0.3048)
			(stroke
				(width 0.1)
				(type default)
			)
			(layer "B.Fab")
		)
		(fp_line
			(start 0.67945 0.3048)
			(end 0.67945 -0.305054)
			(stroke
				(width 0.1)
				(type default)
			)
			(layer "B.Fab")
		)
		(fp_line
			(start -0.120396 0.2794)
			(end 0.12065 0.2794)
			(stroke
				(width 0.1)
				(type default)
			)
			(layer "B.Fab")
		)
		(fp_line
			(start 0.12065 0.2794)
			(end 0.12065 0.3048)
			(stroke
				(width 0.1)
				(type default)
			)
			(layer "B.Fab")
		)
		(fp_line
			(start -0.12065 -0.2794)
			(end -0.12065 -0.3048)
			(stroke
				(width 0.1)
				(type default)
			)
			(layer "B.Fab")
		)
		(fp_line
			(start 0.12065 -0.2794)
			(end -0.12065 -0.2794)
			(stroke
				(width 0.1)
				(type default)
			)
			(layer "B.Fab")
		)
		(fp_line
			(start -0.67945 -0.3048)
			(end -0.67945 0.3048)
			(stroke
				(width 0.1)
				(type default)
			)
			(layer "B.Fab")
		)
		(fp_line
			(start -0.12065 -0.3048)
			(end -0.67945 -0.3048)
			(stroke
				(width 0.1)
				(type default)
			)
			(layer "B.Fab")
		)
		(fp_line
			(start 0.12065 -0.305054)
			(end 0.12065 -0.2794)
			(stroke
				(width 0.1)
				(type default)
			)
			(layer "B.Fab")
		)
		(fp_line
			(start 0.67945 -0.305054)
			(end 0.12065 -0.305054)
			(stroke
				(width 0.1)
				(type default)
			)
			(layer "B.Fab")
		)
		(pad "1" smd circle
			(at 0.40005 0 90)
			(size 0 0)
			(layers "B.Cu" "B.Mask" "B.Paste")
			(net "P0V9_CPU1_RT2_2A")
		)
		(pad "2" smd circle
			(at -0.40005 0 90)
			(size 0 0)
			(layers "B.Cu" "B.Mask" "B.Paste")
			(net "GND")
		)
	)
	(footprint ""
		(layer "B.Cu")
		(at 165.419532 -431.57648 -90)
		(property "Reference" "R4572"
			(at 0 0 90)
			(layer "B.SilkS")
			(hide yes)
			(effects
				(font
					(size 1.27 1.27)
				)
				(justify mirror)
			)
		)
		(property "Value" ""
			(at 0 0 90)
			(layer "B.Fab")
			(effects
				(font
					(size 1.27 1.27)
				)
				(justify mirror)
			)
		)
		(duplicate_pad_numbers_are_jumpers no)
		(fp_line
			(start -0.7874 0.4064)
			(end 0.7874 0.4064)
			(stroke
				(width 0.1524)
				(type default)
			)
			(layer "B.SilkS")
		)
		(fp_line
			(start 0.7874 0.4064)
			(end 0.7874 -0.4064)
			(stroke
				(width 0.1524)
				(type default)
			)
			(layer "B.SilkS")
		)
		(fp_line
			(start -0.7874 -0.4064)
			(end -0.7874 0.4064)
			(stroke
				(width 0.1524)
				(type default)
			)
			(layer "B.SilkS")
		)
		(fp_line
			(start 0.7874 -0.4064)
			(end -0.7874 -0.4064)
			(stroke
				(width 0.1524)
				(type default)
			)
			(layer "B.SilkS")
		)
		(fp_line
			(start -0.67945 0.3048)
			(end -0.120396 0.3048)
			(stroke
				(width 0.1)
				(type default)
			)
			(layer "B.Fab")
		)
		(fp_line
			(start -0.120396 0.3048)
			(end -0.120396 0.2794)
			(stroke
				(width 0.1)
				(type default)
			)
			(layer "B.Fab")
		)
		(fp_line
			(start 0.12065 0.3048)
			(end 0.67945 0.3048)
			(stroke
				(width 0.1)
				(type default)
			)
			(layer "B.Fab")
		)
		(fp_line
			(start 0.67945 0.3048)
			(end 0.67945 -0.305054)
			(stroke
				(width 0.1)
				(type default)
			)
			(layer "B.Fab")
		)
		(fp_line
			(start -0.120396 0.2794)
			(end 0.12065 0.2794)
			(stroke
				(width 0.1)
				(type default)
			)
			(layer "B.Fab")
		)
		(fp_line
			(start 0.12065 0.2794)
			(end 0.12065 0.3048)
			(stroke
				(width 0.1)
				(type default)
			)
			(layer "B.Fab")
		)
		(fp_line
			(start -0.12065 -0.2794)
			(end -0.12065 -0.3048)
			(stroke
				(width 0.1)
				(type default)
			)
			(layer "B.Fab")
		)
		(fp_line
			(start 0.12065 -0.2794)
			(end -0.12065 -0.2794)
			(stroke
				(width 0.1)
				(type default)
			)
			(layer "B.Fab")
		)
		(fp_line
			(start -0.67945 -0.3048)
			(end -0.67945 0.3048)
			(stroke
				(width 0.1)
				(type default)
			)
			(layer "B.Fab")
		)
		(fp_line
			(start -0.12065 -0.3048)
			(end -0.67945 -0.3048)
			(stroke
				(width 0.1)
				(type default)
			)
			(layer "B.Fab")
		)
		(fp_line
			(start 0.12065 -0.305054)
			(end 0.12065 -0.2794)
			(stroke
				(width 0.1)
				(type default)
			)
			(layer "B.Fab")
		)
		(fp_line
			(start 0.67945 -0.305054)
			(end 0.12065 -0.305054)
			(stroke
				(width 0.1)
				(type default)
			)
			(layer "B.Fab")
		)
		(pad "1" smd circle
			(at 0.40005 0 90)
			(size 0 0)
			(layers "B.Cu" "B.Mask" "B.Paste")
			(net "GPU_3V3IO_RSVD1_FFU")
		)
		(pad "2" smd circle
			(at -0.40005 0 90)
			(size 0 0)
			(layers "B.Cu" "B.Mask" "B.Paste")
			(net "GPU_3V3IO_RSVD1_FFU_ISO")
		)
	)
)
